(kicad_pcb
	(version 20221018)
	(generator pcbnew)
	(general
    (thickness 1.7403)
  )
	(paper "A4")
	(title_block
    (title "Data Center RDIMM DDR4 Tester")
    (date "2024-09-30")
    (rev "1.2.4")
		(comment 9 "footprints 224-232 of 690")
	)
	(layers
    (0 "F.Cu" signal)
    (1 "In1.Cu" power)
    (2 "In2.Cu" signal)
    (3 "In3.Cu" power)
    (4 "In4.Cu" power)
    (5 "In5.Cu" signal)
    (6 "In6.Cu" power)
    (7 "In7.Cu" signal)
    (8 "In8.Cu" power)
    (9 "In9.Cu" signal)
    (10 "In10.Cu" power)
    (31 "B.Cu" signal)
    (32 "B.Adhes" user "B.Adhesive")
    (33 "F.Adhes" user "F.Adhesive")
    (34 "B.Paste" user)
    (35 "F.Paste" user)
    (36 "B.SilkS" user "B.Silkscreen")
    (37 "F.SilkS" user "F.Silkscreen")
    (38 "B.Mask" user)
    (39 "F.Mask" user)
    (40 "Dwgs.User" user "User.Drawings")
    (41 "Cmts.User" user "User.Comments")
    (42 "Eco1.User" user "User.Eco1")
    (43 "Eco2.User" user "User.Eco2")
    (44 "Edge.Cuts" user)
    (45 "Margin" user)
    (46 "B.CrtYd" user "B.Courtyard")
    (47 "F.CrtYd" user "F.Courtyard")
    (48 "B.Fab" user)
    (49 "F.Fab" user)
  )
	(footprint "data-center-rdimm-ddr4-tester-footprints:L_1716_4441Metric" (layer "F.Cu")
    (at 138.636328 84.210008 90)
    (property "Author" "Antmicro")
    (property "License" "Apache-2.0")
    (property "MPN" "SRP0420-1R5K")
    (property "Manufacturer" "Bourns")
    (property "MaxCur" "6A")
    (property "Sheetfile" "supply.kicad_sch")
    (property "Sheetname" "Supply")
    (property "Size" "4.40x4.10")
    (property "Val" "1u5/6A")
    (attr smd)
    (fp_text reference "L3" (at 2.460008 -2.656328 180) (layer "F.SilkS")
        (effects (font (size 0.7 0.7) (thickness 0.15)) (justify left bottom))
    )
    (fp_text value "L_1u5_6A_1716" (at 0 3.3 90) (layer "F.Fab") hide
        (effects (font (size 0.7 0.7) (thickness 0.15)) (justify left bottom))
    )
    (fp_text user "License: Apache-2.0" (at -17.726 19.484 90) (layer "F.Fab") hide
        (effects (font (size 0.7 0.7) (thickness 0.15)) (justify left bottom))
    )
    (fp_text user "${REFERENCE}" (at -17.726 17.083 90) (layer "F.Fab") hide
        (effects (font (size 0.7 0.7) (thickness 0.15)) (justify left bottom))
    )
    (fp_text user "Author: Antmicro" (at -17.726 18.283 90) (layer "F.Fab") hide
        (effects (font (size 0.7 0.7) (thickness 0.15)) (justify left bottom))
    )
    (fp_line (start -2.202 -2.0555) (end 2.248 -2.0555)
      (stroke (width 0.15) (type solid)) (layer "F.SilkS"))
    (fp_line (start -2.202 -1.5265) (end -2.202 -2.0555)
      (stroke (width 0.15) (type solid)) (layer "F.SilkS"))
    (fp_line (start -2.202 2.0535) (end -2.202 1.5245)
      (stroke (width 0.15) (type solid)) (layer "F.SilkS"))
    (fp_line (start -2.202 2.0535) (end 2.248 2.0535)
      (stroke (width 0.15) (type solid)) (layer "F.SilkS"))
    (fp_line (start 2.248 -2.0555) (end 2.248 -1.5265)
      (stroke (width 0.15) (type solid)) (layer "F.SilkS"))
    (fp_line (start 2.248 2.0535) (end 2.248 1.5245)
      (stroke (width 0.15) (type solid)) (layer "F.SilkS"))
    (fp_rect (start -2.775 -2.35) (end 2.775 2.35)
      (stroke (width 0.05) (type solid)) (fill none) (layer "F.CrtYd"))
    (fp_line (start -2.202 -2.0555) (end 2.248 -2.0555)
      (stroke (width 0.15) (type solid)) (layer "F.Fab"))
    (fp_line (start -2.202 2.0295) (end -2.202 -2.0305)
      (stroke (width 0.15) (type solid)) (layer "F.Fab"))
    (fp_line (start 2.248 -2.0305) (end 2.248 2.0295)
      (stroke (width 0.15) (type solid)) (layer "F.Fab"))
    (fp_line (start 2.248 2.0535) (end -2.202 2.0535)
      (stroke (width 0.15) (type solid)) (layer "F.Fab"))
    (pad "1" smd roundrect (at -2 -0.0015 90) (size 1.4 1.9) (layers "F.Cu" "F.Paste" "F.Mask") (roundrect_rratio 0.05)
      (net 3 "Net-(U4-SW)") (pintype "passive"))
    (pad "2" smd roundrect (at 2 -0.0015 90) (size 1.4 1.9) (layers "F.Cu" "F.Paste" "F.Mask") (roundrect_rratio 0.05)
      (net 300 "VCC1V0") (pintype "passive"))
  )
	(footprint "data-center-rdimm-ddr4-tester-footprints:L_1716_4441Metric" (layer "F.Cu")
    (at 117.82 108.83 -90)
    (property "Author" "Antmicro")
    (property "License" "Apache-2.0")
    (property "MPN" "SRP0420-1R5K")
    (property "Manufacturer" "Bourns")
    (property "MaxCur" "6A")
    (property "Sheetfile" "supply.kicad_sch")
    (property "Sheetname" "Supply")
    (property "Size" "4.40x4.10")
    (property "Val" "1u5/6A")
    (attr smd)
    (fp_text reference "L5" (at -2.380008 2.326328) (layer "F.SilkS")
        (effects (font (size 0.7 0.7) (thickness 0.15)) (justify left bottom))
    )
    (fp_text value "L_1u5_6A_1716" (at 0 3.3 -90) (layer "F.Fab") hide
        (effects (font (size 0.7 0.7) (thickness 0.15)) (justify left bottom))
    )
    (fp_text user "${REFERENCE}" (at -17.726 17.083 -90) (layer "F.Fab") hide
        (effects (font (size 0.7 0.7) (thickness 0.15)) (justify left bottom))
    )
    (fp_text user "License: Apache-2.0" (at -17.726 19.484 -90) (layer "F.Fab") hide
        (effects (font (size 0.7 0.7) (thickness 0.15)) (justify left bottom))
    )
    (fp_text user "Author: Antmicro" (at -17.726 18.283 -90) (layer "F.Fab") hide
        (effects (font (size 0.7 0.7) (thickness 0.15)) (justify left bottom))
    )
    (fp_line (start -2.202 -2.0555) (end 2.248 -2.0555)
      (stroke (width 0.15) (type solid)) (layer "F.SilkS"))
    (fp_line (start -2.202 -1.5265) (end -2.202 -2.0555)
      (stroke (width 0.15) (type solid)) (layer "F.SilkS"))
    (fp_line (start -2.202 2.0535) (end -2.202 1.5245)
      (stroke (width 0.15) (type solid)) (layer "F.SilkS"))
    (fp_line (start -2.202 2.0535) (end 2.248 2.0535)
      (stroke (width 0.15) (type solid)) (layer "F.SilkS"))
    (fp_line (start 2.248 -2.0555) (end 2.248 -1.5265)
      (stroke (width 0.15) (type solid)) (layer "F.SilkS"))
    (fp_line (start 2.248 2.0535) (end 2.248 1.5245)
      (stroke (width 0.15) (type solid)) (layer "F.SilkS"))
    (fp_rect (start -2.775 -2.35) (end 2.775 2.35)
      (stroke (width 0.05) (type solid)) (fill none) (layer "F.CrtYd"))
    (fp_line (start -2.202 -2.0555) (end 2.248 -2.0555)
      (stroke (width 0.15) (type solid)) (layer "F.Fab"))
    (fp_line (start -2.202 2.0295) (end -2.202 -2.0305)
      (stroke (width 0.15) (type solid)) (layer "F.Fab"))
    (fp_line (start 2.248 -2.0305) (end 2.248 2.0295)
      (stroke (width 0.15) (type solid)) (layer "F.Fab"))
    (fp_line (start 2.248 2.0535) (end -2.202 2.0535)
      (stroke (width 0.15) (type solid)) (layer "F.Fab"))
    (pad "1" smd roundrect (at -2 -0.0015 270) (size 1.4 1.9) (layers "F.Cu" "F.Paste" "F.Mask") (roundrect_rratio 0.05)
      (net 50 "Net-(U9-SW)") (pintype "passive"))
    (pad "2" smd roundrect (at 2 -0.0015 270) (size 1.4 1.9) (layers "F.Cu" "F.Paste" "F.Mask") (roundrect_rratio 0.05)
      (net 304 "VCC3V3") (pintype "passive"))
  )
	(footprint "data-center-rdimm-ddr4-tester-footprints:L_1716_4441Metric" (layer "F.Cu")
    (at 132.386327 88.510008 180)
    (property "Author" "Antmicro")
    (property "License" "Apache-2.0")
    (property "MPN" "SRP0420-1R5K")
    (property "Manufacturer" "Bourns")
    (property "MaxCur" "6A")
    (property "Sheetfile" "supply.kicad_sch")
    (property "Sheetname" "Supply")
    (property "Size" "4.40x4.10")
    (property "Val" "1u5/6A")
    (attr smd)
    (fp_text reference "L7" (at 4.066327 -1.829992 180) (layer "F.SilkS")
        (effects (font (size 0.7 0.7) (thickness 0.15)) (justify left bottom))
    )
    (fp_text value "L_1u5_6A_1716" (at 0 3.3 180) (layer "F.Fab") hide
        (effects (font (size 0.7 0.7) (thickness 0.15)) (justify left bottom))
    )
    (fp_text user "Author: Antmicro" (at -17.726 18.283 180) (layer "F.Fab") hide
        (effects (font (size 0.7 0.7) (thickness 0.15)) (justify left bottom))
    )
    (fp_text user "${REFERENCE}" (at -17.726 17.083 180) (layer "F.Fab") hide
        (effects (font (size 0.7 0.7) (thickness 0.15)) (justify left bottom))
    )
    (fp_text user "License: Apache-2.0" (at -17.726 19.484 180) (layer "F.Fab") hide
        (effects (font (size 0.7 0.7) (thickness 0.15)) (justify left bottom))
    )
    (fp_line (start -2.202 -2.0555) (end 2.248 -2.0555)
      (stroke (width 0.15) (type solid)) (layer "F.SilkS"))
    (fp_line (start -2.202 -1.5265) (end -2.202 -2.0555)
      (stroke (width 0.15) (type solid)) (layer "F.SilkS"))
    (fp_line (start -2.202 2.0535) (end -2.202 1.5245)
      (stroke (width 0.15) (type solid)) (layer "F.SilkS"))
    (fp_line (start -2.202 2.0535) (end 2.248 2.0535)
      (stroke (width 0.15) (type solid)) (layer "F.SilkS"))
    (fp_line (start 2.248 -2.0555) (end 2.248 -1.5265)
      (stroke (width 0.15) (type solid)) (layer "F.SilkS"))
    (fp_line (start 2.248 2.0535) (end 2.248 1.5245)
      (stroke (width 0.15) (type solid)) (layer "F.SilkS"))
    (fp_rect (start -2.775 -2.35) (end 2.775 2.35)
      (stroke (width 0.05) (type solid)) (fill none) (layer "F.CrtYd"))
    (fp_line (start -2.202 -2.0555) (end 2.248 -2.0555)
      (stroke (width 0.15) (type solid)) (layer "F.Fab"))
    (fp_line (start -2.202 2.0295) (end -2.202 -2.0305)
      (stroke (width 0.15) (type solid)) (layer "F.Fab"))
    (fp_line (start 2.248 -2.0305) (end 2.248 2.0295)
      (stroke (width 0.15) (type solid)) (layer "F.Fab"))
    (fp_line (start 2.248 2.0535) (end -2.202 2.0535)
      (stroke (width 0.15) (type solid)) (layer "F.Fab"))
    (pad "1" smd roundrect (at -2 -0.0015 180) (size 1.4 1.9) (layers "F.Cu" "F.Paste" "F.Mask") (roundrect_rratio 0.05)
      (net 52 "Net-(U12-SW)") (pintype "passive"))
    (pad "2" smd roundrect (at 2 -0.0015 180) (size 1.4 1.9) (layers "F.Cu" "F.Paste" "F.Mask") (roundrect_rratio 0.05)
      (net 302 "VCC1V8") (pintype "passive"))
  )
	(footprint "data-center-rdimm-ddr4-tester-footprints:R_0402_1005Metric" (layer "F.Cu")
    (at 141.411328 90.635008 180)
    (descr "Resistor SMD 0402")
    (tags "resistor SMD 0402")
    (property "Author" "Antmicro")
    (property "License" "Apache-2.0")
    (property "MPN" "CR0402-FX-1501GLF")
    (property "Manufacturer" "Bourns")
    (property "Sheetfile" "supply.kicad_sch")
    (property "Sheetname" "Supply")
    (property "Tolerance" "1%")
    (property "Val" "1k5")
    (property "ki_description" "1k5 resistor in 0402 package with 1% tolerance")
    (attr smd)
    (fp_text reference "R39" (at -0.738672 -1.529992 180) (layer "F.SilkS")
        (effects (font (size 0.7 0.7) (thickness 0.15)) (justify left bottom))
    )
    (fp_text value "R_1k5_0402" (at 0 1.4 180) (layer "F.Fab") hide
        (effects (font (size 0.7 0.7) (thickness 0.15)) (justify left bottom))
    )
    (fp_text user "${REFERENCE}" (at -0.95 3.168 180) (layer "F.Fab") hide
        (effects (font (size 0.7 0.7) (thickness 0.15)) (justify left bottom))
    )
    (fp_text user "Author: Antmicro" (at -0.95 4.169 180) (layer "F.Fab") hide
        (effects (font (size 0.7 0.7) (thickness 0.15)) (justify left bottom))
    )
    (fp_text user "License: Apache-2.0" (at -0.95 5.169 180) (layer "F.Fab") hide
        (effects (font (size 0.7 0.7) (thickness 0.15)) (justify left bottom))
    )
    (fp_rect (start -0.93 -0.47) (end 0.93 0.47)
      (stroke (width 0.05) (type solid)) (fill none) (layer "F.CrtYd"))
    (fp_rect (start -0.5 -0.25) (end 0.5 0.25)
      (stroke (width 0.15) (type solid)) (fill none) (layer "F.Fab"))
    (pad "1" smd roundrect (at -0.485 0 180) (size 0.59 0.64) (layers "F.Cu" "F.Paste" "F.Mask") (roundrect_rratio 0.25)
      (net 300 "VCC1V0") (pintype "passive"))
    (pad "2" smd roundrect (at 0.485 0 180) (size 0.59 0.64) (layers "F.Cu" "F.Paste" "F.Mask") (roundrect_rratio 0.25)
      (net 370 "Net-(R39-Pad2)") (pintype "passive"))
  )
	(footprint "data-center-rdimm-ddr4-tester-footprints:R_0402_1005Metric" (layer "F.Cu")
    (at 141.411328 91.660008 180)
    (descr "Resistor SMD 0402")
    (tags "resistor SMD 0402")
    (property "Author" "Antmicro")
    (property "License" "Apache-2.0")
    (property "MPN" "CR0402-FX-1001GLF")
    (property "Manufacturer" "Bourns")
    (property "Sheetfile" "supply.kicad_sch")
    (property "Sheetname" "Supply")
    (property "Tolerance" "1%")
    (property "Val" "1k")
    (property "ki_description" "1k resistor in 0402 package with 1% tolerance")
    (attr smd)
    (fp_text reference "R41" (at -0.738672 -1.529992 180) (layer "F.SilkS")
        (effects (font (size 0.7 0.7) (thickness 0.15)) (justify left bottom))
    )
    (fp_text value "R_1k_0402" (at 0 1.4 180) (layer "F.Fab") hide
        (effects (font (size 0.7 0.7) (thickness 0.15)) (justify left bottom))
    )
    (fp_text user "License: Apache-2.0" (at -0.95 5.169 180) (layer "F.Fab") hide
        (effects (font (size 0.7 0.7) (thickness 0.15)) (justify left bottom))
    )
    (fp_text user "${REFERENCE}" (at -0.95 3.168 180) (layer "F.Fab") hide
        (effects (font (size 0.7 0.7) (thickness 0.15)) (justify left bottom))
    )
    (fp_text user "Author: Antmicro" (at -0.95 4.169 180) (layer "F.Fab") hide
        (effects (font (size 0.7 0.7) (thickness 0.15)) (justify left bottom))
    )
    (fp_rect (start -0.93 -0.47) (end 0.93 0.47)
      (stroke (width 0.05) (type solid)) (fill none) (layer "F.CrtYd"))
    (fp_rect (start -0.5 -0.25) (end 0.5 0.25)
      (stroke (width 0.15) (type solid)) (fill none) (layer "F.Fab"))
    (pad "1" smd roundrect (at -0.485 0 180) (size 0.59 0.64) (layers "F.Cu" "F.Paste" "F.Mask") (roundrect_rratio 0.25)
      (net 370 "Net-(R39-Pad2)") (pintype "passive"))
    (pad "2" smd roundrect (at 0.485 0 180) (size 0.59 0.64) (layers "F.Cu" "F.Paste" "F.Mask") (roundrect_rratio 0.25)
      (net 614 "Net-(U4-FB)") (pintype "passive"))
  )
	(footprint "data-center-rdimm-ddr4-tester-footprints:R_0402_1005Metric" (layer "F.Cu")
    (at 139.886328 91.960008 -90)
    (descr "Resistor SMD 0402")
    (tags "resistor SMD 0402")
    (property "Author" "Antmicro")
    (property "License" "Apache-2.0")
    (property "MPN" "CR0402-FX-1002GLF")
    (property "Manufacturer" "Bourns")
    (property "Sheetfile" "supply.kicad_sch")
    (property "Sheetname" "Supply")
    (property "Tolerance" "1%")
    (property "Val" "10k")
    (property "ki_description" "10k resistor in 0402 package with 1% tolerance")
    (attr smd)
    (fp_text reference "R43" (at 2.179992 -1.183672 -90) (layer "F.SilkS")
        (effects (font (size 0.7 0.7) (thickness 0.15)) (justify left bottom))
    )
    (fp_text value "R_10k_0402" (at 0 1.4 -90) (layer "F.Fab") hide
        (effects (font (size 0.7 0.7) (thickness 0.15)) (justify left bottom))
    )
    (fp_text user "Author: Antmicro" (at -0.95 4.169 -90) (layer "F.Fab") hide
        (effects (font (size 0.7 0.7) (thickness 0.15)) (justify left bottom))
    )
    (fp_text user "${REFERENCE}" (at -0.95 3.168 -90) (layer "F.Fab") hide
        (effects (font (size 0.7 0.7) (thickness 0.15)) (justify left bottom))
    )
    (fp_text user "License: Apache-2.0" (at -0.95 5.169 -90) (layer "F.Fab") hide
        (effects (font (size 0.7 0.7) (thickness 0.15)) (justify left bottom))
    )
    (fp_rect (start -0.93 -0.47) (end 0.93 0.47)
      (stroke (width 0.05) (type solid)) (fill none) (layer "F.CrtYd"))
    (fp_rect (start -0.5 -0.25) (end 0.5 0.25)
      (stroke (width 0.15) (type solid)) (fill none) (layer "F.Fab"))
    (pad "1" smd roundrect (at -0.485 0 270) (size 0.59 0.64) (layers "F.Cu" "F.Paste" "F.Mask") (roundrect_rratio 0.25)
      (net 614 "Net-(U4-FB)") (pintype "passive"))
    (pad "2" smd roundrect (at 0.485 0 270) (size 0.59 0.64) (layers "F.Cu" "F.Paste" "F.Mask") (roundrect_rratio 0.25)
      (net 9 "GND") (pintype "passive"))
  )
	(footprint "data-center-rdimm-ddr4-tester-footprints:R_0402_1005Metric" (layer "F.Cu")
    (at 153.099328 114.102008 -90)
    (descr "Resistor SMD 0402")
    (tags "resistor SMD 0402")
    (property "Author" "Antmicro")
    (property "Current" "1A")
    (property "License" "Apache-2.0")
    (property "MPN" "ERJ2GE0R00X")
    (property "Manufacturer" "Panasonic")
    (property "Sheetfile" "supply.kicad_sch")
    (property "Sheetname" "Supply")
    (property "Tolerance" "")
    (property "Val" "0R")
    (property "ki_description" "0R resistor in 0402 package with unspecified tolerance")
    (attr smd)
    (fp_text reference "R44" (at 1.067992 -3.370672 -90) (layer "F.SilkS")
        (effects (font (size 0.7 0.7) (thickness 0.15)) (justify left bottom))
    )
    (fp_text value "R_0R_0402" (at 0 1.4 -90) (layer "F.Fab") hide
        (effects (font (size 0.7 0.7) (thickness 0.15)) (justify left bottom))
    )
    (fp_text user "License: Apache-2.0" (at -0.95 5.169 -90) (layer "F.Fab") hide
        (effects (font (size 0.7 0.7) (thickness 0.15)) (justify left bottom))
    )
    (fp_text user "Author: Antmicro" (at -0.95 4.169 -90) (layer "F.Fab") hide
        (effects (font (size 0.7 0.7) (thickness 0.15)) (justify left bottom))
    )
    (fp_text user "${REFERENCE}" (at -0.95 3.168 -90) (layer "F.Fab") hide
        (effects (font (size 0.7 0.7) (thickness 0.15)) (justify left bottom))
    )
    (fp_rect (start -0.93 -0.47) (end 0.93 0.47)
      (stroke (width 0.05) (type solid)) (fill none) (layer "F.CrtYd"))
    (fp_rect (start -0.5 -0.25) (end 0.5 0.25)
      (stroke (width 0.15) (type solid)) (fill none) (layer "F.Fab"))
    (pad "1" smd roundrect (at -0.485 0 270) (size 0.59 0.64) (layers "F.Cu" "F.Paste" "F.Mask") (roundrect_rratio 0.25)
      (net 153 "/Supply/VCC_IO_EN") (pintype "passive"))
    (pad "2" smd roundrect (at 0.485 0 270) (size 0.59 0.64) (layers "F.Cu" "F.Paste" "F.Mask") (roundrect_rratio 0.25)
      (net 624 "Net-(U5-EN)") (pintype "passive"))
  )
	(footprint "data-center-rdimm-ddr4-tester-footprints:R_0402_1005Metric" (layer "F.Cu")
    (at 154.149328 114.102008 -90)
    (descr "Resistor SMD 0402")
    (tags "resistor SMD 0402")
    (property "Author" "Antmicro")
    (property "License" "Apache-2.0")
    (property "MPN" "CR0402-FX-4991GLF")
    (property "Manufacturer" "Bourns")
    (property "Sheetfile" "supply.kicad_sch")
    (property "Sheetname" "Supply")
    (property "Tolerance" "1%")
    (property "Val" "4k99")
    (property "ki_description" "4k99 resistor in 0402 package with 1% tolerance")
    (attr smd)
    (fp_text reference "R45" (at 1.067992 -4.110672 -90) (layer "F.SilkS")
        (effects (font (size 0.7 0.7) (thickness 0.15)) (justify left bottom))
    )
    (fp_text value "R_4k99_0402" (at 0 1.4 -90) (layer "F.Fab") hide
        (effects (font (size 0.7 0.7) (thickness 0.15)) (justify left bottom))
    )
    (fp_text user "Author: Antmicro" (at -0.95 4.169 -90) (layer "F.Fab") hide
        (effects (font (size 0.7 0.7) (thickness 0.15)) (justify left bottom))
    )
    (fp_text user "License: Apache-2.0" (at -0.95 5.169 -90) (layer "F.Fab") hide
        (effects (font (size 0.7 0.7) (thickness 0.15)) (justify left bottom))
    )
    (fp_text user "${REFERENCE}" (at -0.95 3.168 -90) (layer "F.Fab") hide
        (effects (font (size 0.7 0.7) (thickness 0.15)) (justify left bottom))
    )
    (fp_rect (start -0.93 -0.47) (end 0.93 0.47)
      (stroke (width 0.05) (type solid)) (fill none) (layer "F.CrtYd"))
    (fp_rect (start -0.5 -0.25) (end 0.5 0.25)
      (stroke (width 0.15) (type solid)) (fill none) (layer "F.Fab"))
    (pad "1" smd roundrect (at -0.485 0 270) (size 0.59 0.64) (layers "F.Cu" "F.Paste" "F.Mask") (roundrect_rratio 0.25)
      (net 176 "VCC1V2") (pintype "passive"))
    (pad "2" smd roundrect (at 0.485 0 270) (size 0.59 0.64) (layers "F.Cu" "F.Paste" "F.Mask") (roundrect_rratio 0.25)
      (net 625 "Net-(U5-FB)") (pintype "passive"))
  )
	(footprint "data-center-rdimm-ddr4-tester-footprints:R_0402_1005Metric" (layer "F.Cu")
    (at 132.536328 95.110008)
    (descr "Resistor SMD 0402")
    (tags "resistor SMD 0402")
    (property "Author" "Antmicro")
    (property "License" "Apache-2.0")
    (property "MPN" "CR0402-FX-1242GLF")
    (property "Manufacturer" "Bourns")
    (property "Sheetfile" "supply.kicad_sch")
    (property "Sheetname" "Supply")
    (property "Tolerance" "1%")
    (property "Val" "12k4")
    (property "ki_description" "12k4 resistor in 0402 package with 1% tolerance")
    (attr smd)
    (fp_text reference "R83" (at 0.643672 0.399992) (layer "F.SilkS")
        (effects (font (size 0.7 0.7) (thickness 0.15)) (justify left bottom))
    )
    (fp_text value "R_12k4_0402" (at 0 1.4) (layer "F.Fab") hide
        (effects (font (size 0.7 0.7) (thickness 0.15)) (justify left bottom))
    )
    (fp_text user "${REFERENCE}" (at -0.95 3.168) (layer "F.Fab") hide
        (effects (font (size 0.7 0.7) (thickness 0.15)) (justify left bottom))
    )
    (fp_text user "Author: Antmicro" (at -0.95 4.169) (layer "F.Fab") hide
        (effects (font (size 0.7 0.7) (thickness 0.15)) (justify left bottom))
    )
    (fp_text user "License: Apache-2.0" (at -0.95 5.169) (layer "F.Fab") hide
        (effects (font (size 0.7 0.7) (thickness 0.15)) (justify left bottom))
    )
    (fp_rect (start -0.93 -0.47) (end 0.93 0.47)
      (stroke (width 0.05) (type solid)) (fill none) (layer "F.CrtYd"))
    (fp_rect (start -0.5 -0.25) (end 0.5 0.25)
      (stroke (width 0.15) (type solid)) (fill none) (layer "F.Fab"))
    (pad "1" smd roundrect (at -0.485 0) (size 0.59 0.64) (layers "F.Cu" "F.Paste" "F.Mask") (roundrect_rratio 0.25)
      (net 302 "VCC1V8") (pintype "passive"))
    (pad "2" smd roundrect (at 0.485 0) (size 0.59 0.64) (layers "F.Cu" "F.Paste" "F.Mask") (roundrect_rratio 0.25)
      (net 653 "Net-(U12-FB)") (pintype "passive"))
  )
)
